# S9S_MB_2U (Grand Teton) — schematic netlist excerpt (pin names and nets, part order shuffled) for the footprints in the layout excerpt that follows; sources: Cadence DE-HDL packaged netlist, KiCad conversion of 03242023_DA0F0TMBIJ0_F0T_Motherboard_J_brd_V01_OCP.brd

R4580  Q_RES  10K 1% EMPTY  pkg 0402LF  page 195 : A = P3V3_AUX ; B = FM_BOARD_BMC_SKU_ID4

U18  74CBTLV3126PW  IC  pkg TSSOP14  page 132
  \1oe\  = PWRGD_PVNN_MAIN_CPU0
  \1a\  = JTAG_DBP_CPU_HOOK9_MBP3_GTL_N
  \1b\  = DBP_CPU_HOOK9_MBP3_GTL_QS_N
  \2oe\  = PWRGD_PVNN_MAIN_CPU0
  \2a\  = JTAG_DBP_CPU_HOOK8_MBP2_GTL_N
  \2b\  = DBP_CPU_HOOK8_MBP2_GTL_QS_N
  GND  = GND
  \3b\  = H_CPU_PRDY_QS_GTL_N
  \3a\  = JTAG_DBP_PRDY_N
  \3oe\  = PWRGD_PVNN_MAIN_CPU0
  \4b\  = H_CPU_PREQ_QS_GTL_N
  \4a\  = JTAG_DBP_PREQ_N
  \4oe\  = PWRGD_PVNN_MAIN_CPU0
  VCC  = P3V3_AUX

(kicad_pcb
	(version 20260206)
	(generator "pcbnew")
	(generator_version "10.0")
	(general
		(thickness 1.6)
		(legacy_teardrops no)
	)
	(paper "A4")
	(title_block
		(title "03242023_DA0F0TMBIJ0_F0T_Motherboard_J_brd_V01_OCP.brd")
		(comment 1 "Grand Teton / footprints 732-733 of 6105")
	)
	(layers
		(0 "F.Cu" signal "TOP")
		(4 "In1.Cu" signal "GND")
		(6 "In2.Cu" signal "IN1")
		(8 "In3.Cu" signal "GND1")
		(10 "In4.Cu" signal "IN2")
		(12 "In5.Cu" signal "GND2")
		(14 "In6.Cu" signal "IN3")
		(16 "In7.Cu" signal "GND3")
		(18 "In8.Cu" signal "VCC")
		(20 "In9.Cu" signal "VCC1")
		(22 "In10.Cu" signal "GND4")
		(24 "In11.Cu" signal "IN4")
		(26 "In12.Cu" signal "GND5")
		(28 "In13.Cu" signal "IN5")
		(30 "In14.Cu" signal "GND6")
		(32 "In15.Cu" signal "IN6")
		(34 "In16.Cu" signal "GND7")
		(2 "B.Cu" signal "BOTTOM")
		(9 "F.Adhes" user "F.Adhesive")
		(11 "B.Adhes" user "B.Adhesive")
		(13 "F.Paste" user "Package Geometry/Pastemask Top")
		(15 "B.Paste" user "Package Geometry/Pastemask Bottom")
		(5 "F.SilkS" user "Ref Des/Silkscreen Top")
		(7 "B.SilkS" user "Ref Des/Silkscreen Bottom")
		(1 "F.Mask" user "Board Geometry/Soldermask Top")
		(3 "B.Mask" user "Board Geometry/Soldermask Bottom")
		(17 "Dwgs.User" user "User.Drawings")
		(19 "Cmts.User" user "User.Comments")
		(21 "Eco1.User" user "User.Eco1")
		(23 "Eco2.User" user "User.Eco2")
		(25 "Edge.Cuts" user "Board Geometry/Outline")
		(27 "Margin" user)
		(31 "F.CrtYd" user "Package Geometry/Place Bound Top")
		(29 "B.CrtYd" user "Package Geometry/Place Bound Bottom")
		(35 "F.Fab" user "Ref Des/Assembly Top")
		(33 "B.Fab" user "Ref Des/Assembly Bottom")
	)
	(footprint ""
		(layer "F.Cu")
		(at 172.8724 -93.538548 90)
		(property "Reference" "R4580"
			(at 0 0 90)
			(layer "F.SilkS")
			(hide yes)
			(effects
				(font
					(size 1.27 1.27)
				)
			)
		)
		(property "Value" ""
			(at 0 0 90)
			(layer "F.Fab")
			(effects
				(font
					(size 1.27 1.27)
				)
			)
		)
		(duplicate_pad_numbers_are_jumpers no)
		(fp_line
			(start 0.7874 -0.4064)
			(end 0.7874 0.4064)
			(stroke
				(width 0.1524)
				(type default)
			)
			(layer "F.SilkS")
		)
		(fp_line
			(start -0.7874 -0.4064)
			(end 0.7874 -0.4064)
			(stroke
				(width 0.1524)
				(type default)
			)
			(layer "F.SilkS")
		)
		(fp_line
			(start 0.7874 0.4064)
			(end -0.7874 0.4064)
			(stroke
				(width 0.1524)
				(type default)
			)
			(layer "F.SilkS")
		)
		(fp_line
			(start -0.7874 0.4064)
			(end -0.7874 -0.4064)
			(stroke
				(width 0.1524)
				(type default)
			)
			(layer "F.SilkS")
		)
		(fp_line
			(start -0.12065 -0.305054)
			(end -0.12065 -0.2794)
			(stroke
				(width 0.1)
				(type default)
			)
			(layer "F.Fab")
		)
		(fp_line
			(start -0.67945 -0.305054)
			(end -0.12065 -0.305054)
			(stroke
				(width 0.1)
				(type default)
			)
			(layer "F.Fab")
		)
		(fp_line
			(start 0.67945 -0.3048)
			(end 0.67945 0.3048)
			(stroke
				(width 0.1)
				(type default)
			)
			(layer "F.Fab")
		)
		(fp_line
			(start 0.12065 -0.3048)
			(end 0.67945 -0.3048)
			(stroke
				(width 0.1)
				(type default)
			)
			(layer "F.Fab")
		)
		(fp_line
			(start 0.12065 -0.2794)
			(end 0.12065 -0.3048)
			(stroke
				(width 0.1)
				(type default)
			)
			(layer "F.Fab")
		)
		(fp_line
			(start -0.12065 -0.2794)
			(end 0.12065 -0.2794)
			(stroke
				(width 0.1)
				(type default)
			)
			(layer "F.Fab")
		)
		(fp_line
			(start 0.120396 0.2794)
			(end -0.12065 0.2794)
			(stroke
				(width 0.1)
				(type default)
			)
			(layer "F.Fab")
		)
		(fp_line
			(start -0.12065 0.2794)
			(end -0.12065 0.3048)
			(stroke
				(width 0.1)
				(type default)
			)
			(layer "F.Fab")
		)
		(fp_line
			(start 0.67945 0.3048)
			(end 0.120396 0.3048)
			(stroke
				(width 0.1)
				(type default)
			)
			(layer "F.Fab")
		)
		(fp_line
			(start 0.120396 0.3048)
			(end 0.120396 0.2794)
			(stroke
				(width 0.1)
				(type default)
			)
			(layer "F.Fab")
		)
		(fp_line
			(start -0.12065 0.3048)
			(end -0.67945 0.3048)
			(stroke
				(width 0.1)
				(type default)
			)
			(layer "F.Fab")
		)
		(fp_line
			(start -0.67945 0.3048)
			(end -0.67945 -0.305054)
			(stroke
				(width 0.1)
				(type default)
			)
			(layer "F.Fab")
		)
		(pad "1" smd rect
			(at -0.40005 0 270)
			(size 0.4572 0.508)
			(layers "F.Cu" "F.Mask" "F.Paste")
			(net "P3V3_AUX")
		)
		(pad "2" smd rect
			(at 0.40005 0 270)
			(size 0.4572 0.508)
			(layers "F.Cu" "F.Mask" "F.Paste")
			(net "FM_BOARD_BMC_SKU_ID4")
		)
	)
	(footprint ""
		(layer "F.Cu")
		(at 367.63452 -65.771268)
		(property "Reference" "U18"
			(at -2.032 -3.27533 0)
			(unlocked yes)
			(layer "F.SilkS")
			(effects
				(font
					(size 0.7874 0.5842)
					(thickness 0.1524)
				)
				(justify left)
			)
		)
		(property "Value" ""
			(at 0 0 0)
			(layer "F.Fab")
			(effects
				(font
					(size 1.27 1.27)
				)
			)
		)
		(duplicate_pad_numbers_are_jumpers no)
		(fp_line
			(start -2.0066 -2.5527)
			(end -0.5715 -2.5527)
			(stroke
				(width 0.1524)
				(type default)
			)
			(layer "F.SilkS")
		)
		(fp_line
			(start -2.0066 2.5527)
			(end -2.0066 -2.5527)
			(stroke
				(width 0.1524)
				(type default)
			)
			(layer "F.SilkS")
		)
		(fp_line
			(start -0.5715 -2.5527)
			(end 0 -1.9812)
			(stroke
				(width 0.1524)
				(type default)
			)
			(layer "F.SilkS")
		)
		(fp_line
			(start 0 -1.9812)
			(end 0.5715 -2.5527)
			(stroke
				(width 0.1524)
				(type default)
			)
			(layer "F.SilkS")
		)
		(fp_line
			(start 0.5715 -2.5527)
			(end 2.0066 -2.5527)
			(stroke
				(width 0.1524)
				(type default)
			)
			(layer "F.SilkS")
		)
		(fp_line
			(start 2.0066 -2.5527)
			(end 2.0066 2.5527)
			(stroke
				(width 0.1524)
				(type default)
			)
			(layer "F.SilkS")
		)
		(fp_line
			(start 2.0066 2.5527)
			(end -2.0066 2.5527)
			(stroke
				(width 0.1524)
				(type default)
			)
			(layer "F.SilkS")
		)
		(fp_poly
			(pts
				(xy -4.36372 -2.233168) (xy -3.81 -1.905) (xy -4.36372 -1.608328)
			)
			(stroke
				(width 0)
				(type default)
			)
			(fill yes)
			(layer "F.SilkS")
		)
		(fp_line
			(start -2.249932 -2.549906)
			(end 2.249932 -2.549906)
			(stroke
				(width 0.1)
				(type default)
			)
			(layer "F.Fab")
		)
		(fp_line
			(start -2.249932 2.549906)
			(end -2.249932 -2.549906)
			(stroke
				(width 0.1)
				(type default)
			)
			(layer "F.Fab")
		)
		(fp_line
			(start 2.249932 -2.549906)
			(end 2.249932 2.549906)
			(stroke
				(width 0.1)
				(type default)
			)
			(layer "F.Fab")
		)
		(fp_line
			(start 2.249932 2.549906)
			(end -2.249932 2.549906)
			(stroke
				(width 0.1)
				(type default)
			)
			(layer "F.Fab")
		)
		(fp_poly
			(pts
				(xy -4.36372 -1.608328) (xy -4.36372 -2.233168) (xy -3.81 -1.905)
			)
			(stroke
				(width 0)
				(type default)
			)
			(fill yes)
			(layer "F.Fab")
		)
		(pad "1" smd rect
			(at -2.921 -1.949958 270)
			(size 0.3556 1.4986)
			(layers "F.Cu" "F.Mask" "F.Paste")
			(net "PWRGD_PVNN_MAIN_CPU0")
		)
		(pad "2" smd rect
			(at -2.921 -1.299972 270)
			(size 0.3556 1.4986)
			(layers "F.Cu" "F.Mask" "F.Paste")
			(net "JTAG_DBP_CPU_HOOK9_MBP3_GTL_N")
		)
		(pad "3" smd rect
			(at -2.921 -0.649986 270)
			(size 0.3556 1.4986)
			(layers "F.Cu" "F.Mask" "F.Paste")
			(net "DBP_CPU_HOOK9_MBP3_GTL_QS_N")
		)
		(pad "4" smd rect
			(at -2.921 0 270)
			(size 0.3556 1.4986)
			(layers "F.Cu" "F.Mask" "F.Paste")
			(net "PWRGD_PVNN_MAIN_CPU0")
		)
		(pad "5" smd rect
			(at -2.921 0.649986 270)
			(size 0.3556 1.4986)
			(layers "F.Cu" "F.Mask" "F.Paste")
			(net "JTAG_DBP_CPU_HOOK8_MBP2_GTL_N")
		)
		(pad "6" smd rect
			(at -2.921 1.299972 270)
			(size 0.3556 1.4986)
			(layers "F.Cu" "F.Mask" "F.Paste")
			(net "DBP_CPU_HOOK8_MBP2_GTL_QS_N")
		)
		(pad "7" smd rect
			(at -2.921 1.949958 270)
			(size 0.3556 1.4986)
			(layers "F.Cu" "F.Mask" "F.Paste")
			(net "GND")
		)
		(pad "8" smd rect
			(at 2.921 1.949958 270)
			(size 0.3556 1.4986)
			(layers "F.Cu" "F.Mask" "F.Paste")
			(net "H_CPU_PRDY_QS_GTL_N")
		)
		(pad "9" smd rect
			(at 2.921 1.299972 270)
			(size 0.3556 1.4986)
			(layers "F.Cu" "F.Mask" "F.Paste")
			(net "JTAG_DBP_PRDY_N")
		)
		(pad "10" smd rect
			(at 2.921 0.649986 270)
			(size 0.3556 1.4986)
			(layers "F.Cu" "F.Mask" "F.Paste")
			(net "PWRGD_PVNN_MAIN_CPU0")
		)
		(pad "11" smd rect
			(at 2.921 0 270)
			(size 0.3556 1.4986)
			(layers "F.Cu" "F.Mask" "F.Paste")
			(net "H_CPU_PREQ_QS_GTL_N")
		)
		(pad "12" smd rect
			(at 2.921 -0.649986 270)
			(size 0.3556 1.4986)
			(layers "F.Cu" "F.Mask" "F.Paste")
			(net "JTAG_DBP_PREQ_N")
		)
		(pad "13" smd rect
			(at 2.921 -1.299972 270)
			(size 0.3556 1.4986)
			(layers "F.Cu" "F.Mask" "F.Paste")
			(net "PWRGD_PVNN_MAIN_CPU0")
		)
		(pad "14" smd rect
			(at 2.921 -1.949958 270)
			(size 0.3556 1.4986)
			(layers "F.Cu" "F.Mask" "F.Paste")
			(net "P3V3_AUX")
		)
	)
)
